(kicad_pcb
	(version 20241229)
	(generator "pcbnew")
	(generator_version "9.0")
	(general
		(thickness 1.61)
		(legacy_teardrops no)
	)
	(paper "A3")
	(title_block
		(title "RDIMM DDR5 Tester")
		(date "2026-05-21")
		(rev "2.2.0")
		(company "Antmicro")
		(comment 9 "footprints 567-571 of 796")
	)
	(layers
		(0 "F.Cu" signal)
		(4 "In1.Cu" power)
		(6 "In2.Cu" mixed)
		(8 "In3.Cu" power)
		(10 "In4.Cu" mixed)
		(12 "In5.Cu" power)
		(14 "In6.Cu" mixed)
		(16 "In7.Cu" power)
		(18 "In8.Cu" power)
		(20 "In9.Cu" mixed)
		(22 "In10.Cu" power)
		(2 "B.Cu" signal)
		(9 "F.Adhes" user "F.Adhesive")
		(11 "B.Adhes" user "B.Adhesive")
		(13 "F.Paste" user)
		(15 "B.Paste" user)
		(5 "F.SilkS" user "F.Silkscreen")
		(7 "B.SilkS" user "B.Silkscreen")
		(1 "F.Mask" user)
		(3 "B.Mask" user)
		(17 "Dwgs.User" user "User.Drawings")
		(19 "Cmts.User" user "User.Comments")
		(21 "Eco1.User" user "User.Eco1")
		(23 "Eco2.User" user "User.Eco2")
		(25 "Edge.Cuts" user)
		(27 "Margin" user)
		(31 "F.CrtYd" user "F.Courtyard")
		(29 "B.CrtYd" user "B.Courtyard")
		(35 "F.Fab" user)
		(33 "B.Fab" user)
	)
	(footprint "antmicro-footprints:C_0402_1005Metric"
		(layer "B.Cu")
		(at 204.02 108.3 180)
		(descr "Capacitor SMD 0402")
		(tags "capacitor SMD 0402")
		(property "Reference" "C8"
			(at -2.52 -0.46 0)
			(layer "B.SilkS")
			(effects
				(font
					(size 0.7 0.7)
					(thickness 0.15)
				)
				(justify left bottom mirror)
			)
		)
		(property "Value" "C_100n_0402"
			(at -1.022927 -2.155213 0)
			(layer "B.Fab")
			(effects
				(font
					(size 0.7 0.7)
					(thickness 0.15)
				)
				(justify left bottom mirror)
			)
		)
		(property "Datasheet" "https://www.murata.com/products/productdetail?partno=GRM155R61H104KE14%23"
			(at 0 0 180)
			(layer "F.Fab")
			(hide yes)
			(effects
				(font
					(size 1.27 1.27)
					(thickness 0.15)
				)
			)
		)
		(property "MPN" "GRM155R61H104KE14D"
			(at 0 0 180)
			(unlocked yes)
			(layer "B.Fab")
			(hide yes)
			(effects
				(font
					(size 1 1)
					(thickness 0.15)
				)
				(justify mirror)
			)
		)
		(property "Manufacturer" "Murata"
			(at 0 0 180)
			(unlocked yes)
			(layer "B.Fab")
			(hide yes)
			(effects
				(font
					(size 1 1)
					(thickness 0.15)
				)
				(justify mirror)
			)
		)
		(property "License" "Apache-2.0"
			(at 0 0 180)
			(unlocked yes)
			(layer "B.Fab")
			(hide yes)
			(effects
				(font
					(size 1 1)
					(thickness 0.15)
				)
				(justify mirror)
			)
		)
		(property "Author" "Antmicro"
			(at 0 0 180)
			(unlocked yes)
			(layer "B.Fab")
			(hide yes)
			(effects
				(font
					(size 1 1)
					(thickness 0.15)
				)
				(justify mirror)
			)
		)
		(property "Val" "100n"
			(at 0 0 180)
			(unlocked yes)
			(layer "B.Fab")
			(hide yes)
			(effects
				(font
					(size 1 1)
					(thickness 0.15)
				)
				(justify mirror)
			)
		)
		(property "Voltage" "50V"
			(at 0 0 180)
			(unlocked yes)
			(layer "B.Fab")
			(hide yes)
			(effects
				(font
					(size 1 1)
					(thickness 0.15)
				)
				(justify mirror)
			)
		)
		(property "Dielectric" "X5R"
			(at 0 0 180)
			(unlocked yes)
			(layer "B.Fab")
			(hide yes)
			(effects
				(font
					(size 1 1)
					(thickness 0.15)
				)
				(justify mirror)
			)
		)
		(sheetname "/DDR5 RDIMM/")
		(sheetfile "ddr5-rdimm.kicad_sch")
		(attr smd)
		(fp_rect
			(start -0.925 0.47)
			(end 0.925 -0.47)
			(stroke
				(width 0.05)
				(type default)
			)
			(fill no)
			(layer "B.CrtYd")
		)
		(fp_line
			(start 0.504 0.25)
			(end 0.504 -0.248)
			(stroke
				(width 0.15)
				(type solid)
			)
			(layer "B.Fab")
		)
		(fp_line
			(start 0.504 -0.248)
			(end -0.494 -0.248)
			(stroke
				(width 0.15)
				(type solid)
			)
			(layer "B.Fab")
		)
		(fp_line
			(start -0.494 0.25)
			(end 0.504 0.25)
			(stroke
				(width 0.15)
				(type solid)
			)
			(layer "B.Fab")
		)
		(fp_line
			(start -0.494 -0.248)
			(end -0.494 0.25)
			(stroke
				(width 0.15)
				(type solid)
			)
			(layer "B.Fab")
		)
		(fp_text user "License: Apache-2.0"
			(at -0.939 -5.799 0)
			(layer "B.Fab")
			(effects
				(font
					(size 0.7 0.7)
					(thickness 0.15)
				)
				(justify left bottom mirror)
			)
		)
		(fp_text user "Author: Antmicro"
			(at -0.939 -3.399 0)
			(layer "B.Fab")
			(effects
				(font
					(size 0.7 0.7)
					(thickness 0.15)
				)
				(justify left bottom mirror)
			)
		)
		(fp_text user "${REFERENCE}"
			(at -0.939 -4.599 0)
			(layer "B.Fab")
			(effects
				(font
					(size 0.7 0.7)
					(thickness 0.15)
				)
				(justify left bottom mirror)
			)
		)
		(pad "1" smd roundrect
			(at -0.48 0 180)
			(size 0.59 0.64)
			(layers "B.Cu" "B.Mask" "B.Paste")
			(roundrect_rratio 0.25)
			(net 1 "GND")
			(pintype "passive")
		)
		(pad "2" smd roundrect
			(at 0.48 0 180)
			(size 0.59 0.64)
			(layers "B.Cu" "B.Mask" "B.Paste")
			(roundrect_rratio 0.25)
			(net 687 "VDDQ")
			(pintype "passive")
		)
	)
	(footprint "antmicro-footprints:R_0402_1005Metric_EIA"
		(layer "B.Cu")
		(at 200.5 154 180)
		(descr "Resistor SMD 0402 (1005 Metric), square (rectangular) end terminal, IPC_7351 nominal, (Body size source: IPC-SM-782 page 76, https://www.pcb-3d.com/wordpress/wp-content/uploads/ipc-sm-782a_amendment_1_and_2.pdf)")
		(tags "resistor 0402")
		(property "Reference" "R14"
			(at -1.1 0.7 0)
			(layer "B.SilkS")
			(effects
				(font
					(size 0.7 0.7)
					(thickness 0.15)
				)
				(justify left bottom mirror)
			)
		)
		(property "Value" "R_10k_0402"
			(at 0 -1.169 0)
			(layer "B.Fab")
			(effects
				(font
					(size 0.7 0.7)
					(thickness 0.15)
				)
				(justify left bottom mirror)
			)
		)
		(property "Datasheet" "https://www.bourns.com/docs/product-datasheets/cr.pdf"
			(at 0 0 180)
			(layer "F.Fab")
			(hide yes)
			(effects
				(font
					(size 1.27 1.27)
					(thickness 0.15)
				)
			)
		)
		(property "MPN" "CR0402-FX-1002GLF"
			(at 0 0 180)
			(unlocked yes)
			(layer "B.Fab")
			(hide yes)
			(effects
				(font
					(size 1 1)
					(thickness 0.15)
				)
				(justify mirror)
			)
		)
		(property "Manufacturer" "Bourns"
			(at 0 0 180)
			(unlocked yes)
			(layer "B.Fab")
			(hide yes)
			(effects
				(font
					(size 1 1)
					(thickness 0.15)
				)
				(justify mirror)
			)
		)
		(property "License" "Apache-2.0"
			(at 0 0 180)
			(unlocked yes)
			(layer "B.Fab")
			(hide yes)
			(effects
				(font
					(size 1 1)
					(thickness 0.15)
				)
				(justify mirror)
			)
		)
		(property "Author" "Antmicro"
			(at 0 0 180)
			(unlocked yes)
			(layer "B.Fab")
			(hide yes)
			(effects
				(font
					(size 1 1)
					(thickness 0.15)
				)
				(justify mirror)
			)
		)
		(property "Val" "10k"
			(at 0 0 180)
			(unlocked yes)
			(layer "B.Fab")
			(hide yes)
			(effects
				(font
					(size 1 1)
					(thickness 0.15)
				)
				(justify mirror)
			)
		)
		(property "Tolerance" "1%"
			(at 0 0 180)
			(unlocked yes)
			(layer "B.Fab")
			(hide yes)
			(effects
				(font
					(size 1 1)
					(thickness 0.15)
				)
				(justify mirror)
			)
		)
		(sheetname "/FPGA Config/")
		(sheetfile "fpga-config.kicad_sch")
		(attr smd)
		(fp_rect
			(start -0.95 0.45)
			(end 0.95 -0.45)
			(stroke
				(width 0.05)
				(type default)
			)
			(fill no)
			(layer "B.CrtYd")
		)
		(fp_line
			(start 0.499 0.25)
			(end 0.499 -0.249)
			(stroke
				(width 0.15)
				(type solid)
			)
			(layer "B.Fab")
		)
		(fp_line
			(start 0.499 -0.249)
			(end -0.5 -0.249)
			(stroke
				(width 0.15)
				(type solid)
			)
			(layer "B.Fab")
		)
		(fp_line
			(start -0.5 0.25)
			(end 0.499 0.25)
			(stroke
				(width 0.15)
				(type solid)
			)
			(layer "B.Fab")
		)
		(fp_line
			(start -0.5 -0.249)
			(end -0.5 0.25)
			(stroke
				(width 0.15)
				(type solid)
			)
			(layer "B.Fab")
		)
		(fp_text user "${REFERENCE}"
			(at -0.95 -3.169 0)
			(layer "B.Fab")
			(effects
				(font
					(size 0.7 0.7)
					(thickness 0.15)
				)
				(justify left bottom mirror)
			)
		)
		(fp_text user "Author: Antmicro"
			(at -0.95 -5.569 0)
			(layer "B.Fab")
			(effects
				(font
					(size 0.7 0.7)
					(thickness 0.15)
				)
				(justify left bottom mirror)
			)
		)
		(fp_text user "License: Apache-2.0"
			(at -0.95 -4.369 0)
			(layer "B.Fab")
			(effects
				(font
					(size 0.7 0.7)
					(thickness 0.15)
				)
				(justify left bottom mirror)
			)
		)
		(pad "1" smd roundrect
			(at -0.5 0 90)
			(size 0.6 0.6)
			(layers "B.Cu" "B.Mask" "B.Paste")
			(roundrect_rratio 0.25)
			(net 773 "MODE2")
			(pintype "passive")
		)
		(pad "2" smd roundrect
			(at 0.499 0 180)
			(size 0.6 0.6)
			(layers "B.Cu" "B.Mask" "B.Paste")
			(roundrect_rratio 0.25)
			(net 797 "+1V8")
			(pintype "passive")
		)
	)
	(footprint "antmicro-footprints:R_0402_1005Metric"
		(layer "B.Cu")
		(at 244.86 117.11)
		(descr "Resistor SMD 0402")
		(tags "resistor SMD 0402")
		(property "Reference" "R249"
			(at -1.4 -0.57 0)
			(layer "B.SilkS")
			(effects
				(font
					(size 0.7 0.7)
					(thickness 0.15)
				)
				(justify right bottom mirror)
			)
		)
		(property "Value" "R_47k_0402"
			(at -1.011843 -1.772047 0)
			(layer "B.Fab")
			(effects
				(font
					(size 0.7 0.7)
					(thickness 0.15)
				)
				(justify right bottom mirror)
			)
		)
		(property "Datasheet" "https://www.bourns.com/docs/product-datasheets/cr.pdf"
			(at 0 0 0)
			(layer "F.Fab")
			(hide yes)
			(effects
				(font
					(size 1.27 1.27)
					(thickness 0.15)
				)
			)
		)
		(property "MPN" "CR0402-FX-4702GLF"
			(at 0 0 0)
			(unlocked yes)
			(layer "B.Fab")
			(hide yes)
			(effects
				(font
					(size 1 1)
					(thickness 0.15)
				)
				(justify mirror)
			)
		)
		(property "Manufacturer" "Bourns"
			(at 0 0 0)
			(unlocked yes)
			(layer "B.Fab")
			(hide yes)
			(effects
				(font
					(size 1 1)
					(thickness 0.15)
				)
				(justify mirror)
			)
		)
		(property "License" "Apache-2.0"
			(at 0 0 0)
			(unlocked yes)
			(layer "B.Fab")
			(hide yes)
			(effects
				(font
					(size 1 1)
					(thickness 0.15)
				)
				(justify mirror)
			)
		)
		(property "Author" "Antmicro"
			(at 0 0 0)
			(unlocked yes)
			(layer "B.Fab")
			(hide yes)
			(effects
				(font
					(size 1 1)
					(thickness 0.15)
				)
				(justify mirror)
			)
		)
		(property "Val" "47k"
			(at 0 0 0)
			(unlocked yes)
			(layer "B.Fab")
			(hide yes)
			(effects
				(font
					(size 1 1)
					(thickness 0.15)
				)
				(justify mirror)
			)
		)
		(property "Tolerance" "1%"
			(at 0 0 0)
			(unlocked yes)
			(layer "B.Fab")
			(hide yes)
			(effects
				(font
					(size 1 1)
					(thickness 0.15)
				)
				(justify mirror)
			)
		)
		(sheetname "/Supply/")
		(sheetfile "supply.kicad_sch")
		(attr smd)
		(fp_rect
			(start -0.925 0.47)
			(end 0.925 -0.47)
			(stroke
				(width 0.05)
				(type default)
			)
			(fill no)
			(layer "B.CrtYd")
		)
		(fp_rect
			(start -0.5 0.25)
			(end 0.5 -0.25)
			(stroke
				(width 0.15)
				(type solid)
			)
			(fill no)
			(layer "B.Fab")
		)
		(fp_text user "License: Apache-2.0"
			(at -0.95 -5.169 180)
			(layer "B.Fab")
			(effects
				(font
					(size 0.7 0.7)
					(thickness 0.15)
				)
				(justify left bottom mirror)
			)
		)
		(fp_text user "Author: Antmicro"
			(at -0.95 -4.169 180)
			(layer "B.Fab")
			(effects
				(font
					(size 0.7 0.7)
					(thickness 0.15)
				)
				(justify left bottom mirror)
			)
		)
		(fp_text user "${REFERENCE}"
			(at -0.95 -3.168 180)
			(layer "B.Fab")
			(effects
				(font
					(size 0.7 0.7)
					(thickness 0.15)
				)
				(justify left bottom mirror)
			)
		)
		(pad "1" smd roundrect
			(at -0.48 0)
			(size 0.59 0.64)
			(layers "B.Cu" "B.Mask" "B.Paste")
			(roundrect_rratio 0.25)
			(net 813 "Net-(Q28-D)")
			(pintype "passive")
		)
		(pad "2" smd roundrect
			(at 0.48 0)
			(size 0.59 0.64)
			(layers "B.Cu" "B.Mask" "B.Paste")
			(roundrect_rratio 0.25)
			(net 35 "VDC")
			(pintype "passive")
		)
	)
	(footprint "antmicro-footprints:R_0402_1005Metric"
		(layer "B.Cu")
		(at 260.549499 176.104 90)
		(descr "Resistor SMD 0402")
		(tags "resistor SMD 0402")
		(property "Reference" "R207"
			(at -3.746 0.450501 90)
			(layer "B.SilkS")
			(effects
				(font
					(size 0.7 0.7)
					(thickness 0.15)
				)
				(justify right bottom mirror)
			)
		)
		(property "Value" "R_0R_0402"
			(at -1.011843 -1.772047 90)
			(layer "B.Fab")
			(effects
				(font
					(size 0.7 0.7)
					(thickness 0.15)
				)
				(justify right bottom mirror)
			)
		)
		(property "Datasheet" "https://industrial.panasonic.com/cdbs/www-data/pdf/RDA0000/AOA0000C301.pdf"
			(at 0 0 90)
			(layer "F.Fab")
			(hide yes)
			(effects
				(font
					(size 1.27 1.27)
					(thickness 0.15)
				)
			)
		)
		(property "Manufacturer" "Panasonic"
			(at 0 0 90)
			(unlocked yes)
			(layer "B.Fab")
			(hide yes)
			(effects
				(font
					(size 1 1)
					(thickness 0.15)
				)
				(justify mirror)
			)
		)
		(property "MPN" "ERJ2GE0R00X"
			(at 0 0 90)
			(unlocked yes)
			(layer "B.Fab")
			(hide yes)
			(effects
				(font
					(size 1 1)
					(thickness 0.15)
				)
				(justify mirror)
			)
		)
		(property "Val" "0R"
			(at 0 0 90)
			(unlocked yes)
			(layer "B.Fab")
			(hide yes)
			(effects
				(font
					(size 1 1)
					(thickness 0.15)
				)
				(justify mirror)
			)
		)
		(property "License" "Apache-2.0"
			(at 0 0 90)
			(unlocked yes)
			(layer "B.Fab")
			(hide yes)
			(effects
				(font
					(size 1 1)
					(thickness 0.15)
				)
				(justify mirror)
			)
		)
		(property "Author" "Antmicro"
			(at 0 0 90)
			(unlocked yes)
			(layer "B.Fab")
			(hide yes)
			(effects
				(font
					(size 1 1)
					(thickness 0.15)
				)
				(justify mirror)
			)
		)
		(property "Tolerance" "~"
			(at 0 0 90)
			(unlocked yes)
			(layer "B.Fab")
			(hide yes)
			(effects
				(font
					(size 1 1)
					(thickness 0.15)
				)
				(justify mirror)
			)
		)
		(property "Current" "1A"
			(at 0 0 90)
			(unlocked yes)
			(layer "B.Fab")
			(hide yes)
			(effects
				(font
					(size 1 1)
					(thickness 0.15)
				)
				(justify mirror)
			)
		)
		(sheetname "/Supply/DC-DC AUX, MGT/")
		(sheetfile "dc-dc-aux-mgt.kicad_sch")
		(attr smd exclude_from_bom dnp)
		(fp_rect
			(start -0.925 0.47)
			(end 0.925 -0.47)
			(stroke
				(width 0.05)
				(type default)
			)
			(fill no)
			(layer "B.CrtYd")
		)
		(fp_rect
			(start -0.5 0.25)
			(end 0.5 -0.25)
			(stroke
				(width 0.15)
				(type solid)
			)
			(fill no)
			(layer "B.Fab")
		)
		(fp_text user "License: Apache-2.0"
			(at -0.95 -5.169 270)
			(layer "B.Fab")
			(effects
				(font
					(size 0.7 0.7)
					(thickness 0.15)
				)
				(justify left bottom mirror)
			)
		)
		(fp_text user "${REFERENCE}"
			(at -0.95 -3.168 270)
			(layer "B.Fab")
			(effects
				(font
					(size 0.7 0.7)
					(thickness 0.15)
				)
				(justify left bottom mirror)
			)
		)
		(fp_text user "Author: Antmicro"
			(at -0.95 -4.169 270)
			(layer "B.Fab")
			(effects
				(font
					(size 0.7 0.7)
					(thickness 0.15)
				)
				(justify left bottom mirror)
			)
		)
		(pad "1" smd roundrect
			(at -0.48 0 90)
			(size 0.59 0.64)
			(layers "B.Cu" "B.Mask" "B.Paste")
			(roundrect_rratio 0.25)
			(net 1 "GND")
			(pintype "passive")
		)
		(pad "2" smd roundrect
			(at 0.48 0 90)
			(size 0.59 0.64)
			(layers "B.Cu" "B.Mask" "B.Paste")
			(roundrect_rratio 0.25)
			(net 717 "/Supply/DC-DC AUX, MGT/FB4")
			(pintype "passive")
		)
	)
	(footprint "antmicro-footprints:R_0402_1005Metric"
		(layer "B.Cu")
		(at 203.25 138.1045 180)
		(descr "Resistor SMD 0402")
		(tags "resistor SMD 0402")
		(property "Reference" "R255"
			(at 2.35 0 0)
			(layer "B.SilkS")
			(effects
				(font
					(size 0.7 0.7)
					(thickness 0.15)
				)
				(justify mirror)
			)
		)
		(property "Value" "R_0R_0402"
			(at -1.011843 -1.772047 0)
			(layer "B.Fab")
			(effects
				(font
					(size 0.7 0.7)
					(thickness 0.15)
				)
				(justify left bottom mirror)
			)
		)
		(property "Datasheet" "https://industrial.panasonic.com/cdbs/www-data/pdf/RDA0000/AOA0000C301.pdf"
			(at 0 0 0)
			(layer "B.Fab")
			(hide yes)
			(effects
				(font
					(size 1.27 1.27)
					(thickness 0.15)
				)
				(justify mirror)
			)
		)
		(property "MPN" "ERJ2GE0R00X"
			(at 0 0 0)
			(unlocked yes)
			(layer "B.Fab")
			(hide yes)
			(effects
				(font
					(size 1 1)
					(thickness 0.15)
				)
				(justify mirror)
			)
		)
		(property "Manufacturer" "Panasonic"
			(at 0 0 0)
			(unlocked yes)
			(layer "B.Fab")
			(hide yes)
			(effects
				(font
					(size 1 1)
					(thickness 0.15)
				)
				(justify mirror)
			)
		)
		(property "License" "Apache-2.0"
			(at 0 0 0)
			(unlocked yes)
			(layer "B.Fab")
			(hide yes)
			(effects
				(font
					(size 1 1)
					(thickness 0.15)
				)
				(justify mirror)
			)
		)
		(property "Author" "Antmicro"
			(at 0 0 0)
			(unlocked yes)
			(layer "B.Fab")
			(hide yes)
			(effects
				(font
					(size 1 1)
					(thickness 0.15)
				)
				(justify mirror)
			)
		)
		(property "Val" "0R"
			(at 0 0 0)
			(unlocked yes)
			(layer "B.Fab")
			(hide yes)
			(effects
				(font
					(size 1 1)
					(thickness 0.15)
				)
				(justify mirror)
			)
		)
		(property "Tolerance" "~"
			(at 0 0 0)
			(unlocked yes)
			(layer "B.Fab")
			(hide yes)
			(effects
				(font
					(size 1 1)
					(thickness 0.15)
				)
				(justify mirror)
			)
		)
		(property "Current" "1A"
			(at 0 0 0)
			(unlocked yes)
			(layer "B.Fab")
			(hide yes)
			(effects
				(font
					(size 1 1)
					(thickness 0.15)
				)
				(justify mirror)
			)
		)
		(sheetname "/FPGA banks HP/")
		(sheetfile "fpga-hp-banks.kicad_sch")
		(attr smd)
		(fp_rect
			(start -0.925 0.47)
			(end 0.925 -0.47)
			(stroke
				(width 0.05)
				(type default)
			)
			(fill no)
			(layer "B.CrtYd")
		)
		(fp_rect
			(start -0.5 0.25)
			(end 0.5 -0.25)
			(stroke
				(width 0.15)
				(type solid)
			)
			(fill no)
			(layer "B.Fab")
		)
		(fp_text user "Author: Antmicro"
			(at -0.95 -4.169 0)
			(layer "B.Fab")
			(effects
				(font
					(size 0.7 0.7)
					(thickness 0.15)
				)
				(justify left bottom mirror)
			)
		)
		(fp_text user "${REFERENCE}"
			(at -0.95 -3.168 0)
			(layer "B.Fab")
			(effects
				(font
					(size 0.7 0.7)
					(thickness 0.15)
				)
				(justify left bottom mirror)
			)
		)
		(fp_text user "License: Apache-2.0"
			(at -0.95 -5.169 0)
			(layer "B.Fab")
			(effects
				(font
					(size 0.7 0.7)
					(thickness 0.15)
				)
				(justify left bottom mirror)
			)
		)
		(pad "1" smd roundrect
			(at -0.48 0 180)
			(size 0.59 0.64)
			(layers "B.Cu" "B.Mask" "B.Paste")
			(roundrect_rratio 0.25)
			(net 825 "DAC_VREF")
			(pintype "passive")
		)
		(pad "2" smd roundrect
			(at 0.48 0 180)
			(size 0.59 0.64)
			(layers "B.Cu" "B.Mask" "B.Paste")
			(roundrect_rratio 0.25)
			(net 826 "/FPGA banks HP/VREF")
			(pintype "passive")
		)
	)
)
